(kicad_pcb
	(version 20260206)
	(generator "pcbnew")
	(generator_version "10.0")
	(general
		(thickness 1.6)
		(legacy_teardrops no)
	)
	(paper "A4")
	(title_block
		(title "03242023_DA0F0TMBIJ0_F0T_Motherboard_J_brd_V01_OCP.brd")
		(comment 1 "Grand Teton / footprints 1794-1799 of 6105")
	)
	(layers
		(0 "F.Cu" signal "TOP")
		(4 "In1.Cu" signal "GND")
		(6 "In2.Cu" signal "IN1")
		(8 "In3.Cu" signal "GND1")
		(10 "In4.Cu" signal "IN2")
		(12 "In5.Cu" signal "GND2")
		(14 "In6.Cu" signal "IN3")
		(16 "In7.Cu" signal "GND3")
		(18 "In8.Cu" signal "VCC")
		(20 "In9.Cu" signal "VCC1")
		(22 "In10.Cu" signal "GND4")
		(24 "In11.Cu" signal "IN4")
		(26 "In12.Cu" signal "GND5")
		(28 "In13.Cu" signal "IN5")
		(30 "In14.Cu" signal "GND6")
		(32 "In15.Cu" signal "IN6")
		(34 "In16.Cu" signal "GND7")
		(2 "B.Cu" signal "BOTTOM")
		(9 "F.Adhes" user "F.Adhesive")
		(11 "B.Adhes" user "B.Adhesive")
		(13 "F.Paste" user "Package Geometry/Pastemask Top")
		(15 "B.Paste" user "Package Geometry/Pastemask Bottom")
		(5 "F.SilkS" user "Ref Des/Silkscreen Top")
		(7 "B.SilkS" user "Ref Des/Silkscreen Bottom")
		(1 "F.Mask" user "Board Geometry/Soldermask Top")
		(3 "B.Mask" user "Board Geometry/Soldermask Bottom")
		(17 "Dwgs.User" user "User.Drawings")
		(19 "Cmts.User" user "User.Comments")
		(21 "Eco1.User" user "User.Eco1")
		(23 "Eco2.User" user "User.Eco2")
		(25 "Edge.Cuts" user "Board Geometry/Outline")
		(27 "Margin" user)
		(31 "F.CrtYd" user "Package Geometry/Place Bound Top")
		(29 "B.CrtYd" user "Package Geometry/Place Bound Bottom")
		(35 "F.Fab" user "Ref Des/Assembly Top")
		(33 "B.Fab" user "Ref Des/Assembly Bottom")
	)
	(footprint ""
		(layer "F.Cu")
		(at 364.82782 -333.804514 -90)
		(property "Reference" "PC277_P0_3"
			(at 0 0 270)
			(layer "F.SilkS")
			(hide yes)
			(effects
				(font
					(size 1.27 1.27)
				)
			)
		)
		(property "Value" ""
			(at 0 0 270)
			(layer "F.Fab")
			(effects
				(font
					(size 1.27 1.27)
				)
			)
		)
		(duplicate_pad_numbers_are_jumpers no)
		(fp_line
			(start -0.7874 0.4064)
			(end -0.7874 -0.4064)
			(stroke
				(width 0.1524)
				(type default)
			)
			(layer "F.SilkS")
		)
		(fp_line
			(start 0.7874 0.4064)
			(end -0.7874 0.4064)
			(stroke
				(width 0.1524)
				(type default)
			)
			(layer "F.SilkS")
		)
		(fp_line
			(start -0.7874 -0.4064)
			(end 0.7874 -0.4064)
			(stroke
				(width 0.1524)
				(type default)
			)
			(layer "F.SilkS")
		)
		(fp_line
			(start 0.7874 -0.4064)
			(end 0.7874 0.4064)
			(stroke
				(width 0.1524)
				(type default)
			)
			(layer "F.SilkS")
		)
		(fp_line
			(start -0.67945 0.3048)
			(end -0.67945 -0.305054)
			(stroke
				(width 0.1)
				(type default)
			)
			(layer "F.Fab")
		)
		(fp_line
			(start -0.12065 0.3048)
			(end -0.67945 0.3048)
			(stroke
				(width 0.1)
				(type default)
			)
			(layer "F.Fab")
		)
		(fp_line
			(start 0.120396 0.3048)
			(end 0.120396 0.2794)
			(stroke
				(width 0.1)
				(type default)
			)
			(layer "F.Fab")
		)
		(fp_line
			(start 0.67945 0.3048)
			(end 0.120396 0.3048)
			(stroke
				(width 0.1)
				(type default)
			)
			(layer "F.Fab")
		)
		(fp_line
			(start -0.12065 0.2794)
			(end -0.12065 0.3048)
			(stroke
				(width 0.1)
				(type default)
			)
			(layer "F.Fab")
		)
		(fp_line
			(start 0.120396 0.2794)
			(end -0.12065 0.2794)
			(stroke
				(width 0.1)
				(type default)
			)
			(layer "F.Fab")
		)
		(fp_line
			(start -0.12065 -0.2794)
			(end 0.12065 -0.2794)
			(stroke
				(width 0.1)
				(type default)
			)
			(layer "F.Fab")
		)
		(fp_line
			(start 0.12065 -0.2794)
			(end 0.12065 -0.3048)
			(stroke
				(width 0.1)
				(type default)
			)
			(layer "F.Fab")
		)
		(fp_line
			(start 0.12065 -0.3048)
			(end 0.67945 -0.3048)
			(stroke
				(width 0.1)
				(type default)
			)
			(layer "F.Fab")
		)
		(fp_line
			(start 0.67945 -0.3048)
			(end 0.67945 0.3048)
			(stroke
				(width 0.1)
				(type default)
			)
			(layer "F.Fab")
		)
		(fp_line
			(start -0.67945 -0.305054)
			(end -0.12065 -0.305054)
			(stroke
				(width 0.1)
				(type default)
			)
			(layer "F.Fab")
		)
		(fp_line
			(start -0.12065 -0.305054)
			(end -0.12065 -0.2794)
			(stroke
				(width 0.1)
				(type default)
			)
			(layer "F.Fab")
		)
		(pad "1" smd circle
			(at -0.40005 0 270)
			(size 0 0)
			(layers "F.Cu" "F.Mask" "F.Paste")
			(net "SW_P12V_PVCCIN_CPU0_FLT")
		)
		(pad "2" smd circle
			(at 0.40005 0 270)
			(size 0 0)
			(layers "F.Cu" "F.Mask" "F.Paste")
			(net "GND")
		)
	)
	(footprint ""
		(layer "F.Cu")
		(at 294.62222 -421.41521 90)
		(property "Reference" "R4153"
			(at 0 0 90)
			(layer "F.SilkS")
			(hide yes)
			(effects
				(font
					(size 1.27 1.27)
				)
			)
		)
		(property "Value" ""
			(at 0 0 90)
			(layer "F.Fab")
			(effects
				(font
					(size 1.27 1.27)
				)
			)
		)
		(duplicate_pad_numbers_are_jumpers no)
		(fp_line
			(start 0.7874 -0.4064)
			(end 0.7874 0.4064)
			(stroke
				(width 0.1524)
				(type default)
			)
			(layer "F.SilkS")
		)
		(fp_line
			(start -0.7874 -0.4064)
			(end 0.7874 -0.4064)
			(stroke
				(width 0.1524)
				(type default)
			)
			(layer "F.SilkS")
		)
		(fp_line
			(start 0.7874 0.4064)
			(end -0.7874 0.4064)
			(stroke
				(width 0.1524)
				(type default)
			)
			(layer "F.SilkS")
		)
		(fp_line
			(start -0.7874 0.4064)
			(end -0.7874 -0.4064)
			(stroke
				(width 0.1524)
				(type default)
			)
			(layer "F.SilkS")
		)
		(fp_line
			(start -0.12065 -0.305054)
			(end -0.12065 -0.2794)
			(stroke
				(width 0.1)
				(type default)
			)
			(layer "F.Fab")
		)
		(fp_line
			(start -0.67945 -0.305054)
			(end -0.12065 -0.305054)
			(stroke
				(width 0.1)
				(type default)
			)
			(layer "F.Fab")
		)
		(fp_line
			(start 0.67945 -0.3048)
			(end 0.67945 0.3048)
			(stroke
				(width 0.1)
				(type default)
			)
			(layer "F.Fab")
		)
		(fp_line
			(start 0.12065 -0.3048)
			(end 0.67945 -0.3048)
			(stroke
				(width 0.1)
				(type default)
			)
			(layer "F.Fab")
		)
		(fp_line
			(start 0.12065 -0.2794)
			(end 0.12065 -0.3048)
			(stroke
				(width 0.1)
				(type default)
			)
			(layer "F.Fab")
		)
		(fp_line
			(start -0.12065 -0.2794)
			(end 0.12065 -0.2794)
			(stroke
				(width 0.1)
				(type default)
			)
			(layer "F.Fab")
		)
		(fp_line
			(start 0.120396 0.2794)
			(end -0.12065 0.2794)
			(stroke
				(width 0.1)
				(type default)
			)
			(layer "F.Fab")
		)
		(fp_line
			(start -0.12065 0.2794)
			(end -0.12065 0.3048)
			(stroke
				(width 0.1)
				(type default)
			)
			(layer "F.Fab")
		)
		(fp_line
			(start 0.67945 0.3048)
			(end 0.120396 0.3048)
			(stroke
				(width 0.1)
				(type default)
			)
			(layer "F.Fab")
		)
		(fp_line
			(start 0.120396 0.3048)
			(end 0.120396 0.2794)
			(stroke
				(width 0.1)
				(type default)
			)
			(layer "F.Fab")
		)
		(fp_line
			(start -0.12065 0.3048)
			(end -0.67945 0.3048)
			(stroke
				(width 0.1)
				(type default)
			)
			(layer "F.Fab")
		)
		(fp_line
			(start -0.67945 0.3048)
			(end -0.67945 -0.305054)
			(stroke
				(width 0.1)
				(type default)
			)
			(layer "F.Fab")
		)
		(pad "1" smd circle
			(at -0.40005 0 90)
			(size 0 0)
			(layers "F.Cu" "F.Mask" "F.Paste")
			(net "P3V3_AUX")
		)
		(pad "2" smd circle
			(at 0.40005 0 90)
			(size 0 0)
			(layers "F.Cu" "F.Mask" "F.Paste")
			(net "PRSNT_CABLE_GPU_A1_N")
		)
	)
	(footprint ""
		(layer "F.Cu")
		(at 158.901384 -43.832526 90)
		(property "Reference" "R4471"
			(at 0 0 90)
			(layer "F.SilkS")
			(hide yes)
			(effects
				(font
					(size 1.27 1.27)
				)
			)
		)
		(property "Value" ""
			(at 0 0 90)
			(layer "F.Fab")
			(effects
				(font
					(size 1.27 1.27)
				)
			)
		)
		(duplicate_pad_numbers_are_jumpers no)
		(fp_line
			(start 0.7874 -0.4064)
			(end 0.7874 0.4064)
			(stroke
				(width 0.1524)
				(type default)
			)
			(layer "F.SilkS")
		)
		(fp_line
			(start -0.7874 -0.4064)
			(end 0.7874 -0.4064)
			(stroke
				(width 0.1524)
				(type default)
			)
			(layer "F.SilkS")
		)
		(fp_line
			(start -0.12065 -0.305054)
			(end -0.12065 -0.2794)
			(stroke
				(width 0.1)
				(type default)
			)
			(layer "F.Fab")
		)
		(fp_line
			(start -0.67945 -0.305054)
			(end -0.12065 -0.305054)
			(stroke
				(width 0.1)
				(type default)
			)
			(layer "F.Fab")
		)
		(fp_line
			(start 0.67945 -0.3048)
			(end 0.67945 0.3048)
			(stroke
				(width 0.1)
				(type default)
			)
			(layer "F.Fab")
		)
		(fp_line
			(start 0.12065 -0.3048)
			(end 0.67945 -0.3048)
			(stroke
				(width 0.1)
				(type default)
			)
			(layer "F.Fab")
		)
		(fp_line
			(start 0.12065 -0.2794)
			(end 0.12065 -0.3048)
			(stroke
				(width 0.1)
				(type default)
			)
			(layer "F.Fab")
		)
		(fp_line
			(start -0.12065 -0.2794)
			(end 0.12065 -0.2794)
			(stroke
				(width 0.1)
				(type default)
			)
			(layer "F.Fab")
		)
		(fp_line
			(start 0.120396 0.2794)
			(end -0.12065 0.2794)
			(stroke
				(width 0.1)
				(type default)
			)
			(layer "F.Fab")
		)
		(fp_line
			(start -0.12065 0.2794)
			(end -0.12065 0.3048)
			(stroke
				(width 0.1)
				(type default)
			)
			(layer "F.Fab")
		)
		(fp_line
			(start 0.67945 0.3048)
			(end 0.120396 0.3048)
			(stroke
				(width 0.1)
				(type default)
			)
			(layer "F.Fab")
		)
		(fp_line
			(start 0.120396 0.3048)
			(end 0.120396 0.2794)
			(stroke
				(width 0.1)
				(type default)
			)
			(layer "F.Fab")
		)
		(fp_line
			(start -0.12065 0.3048)
			(end -0.67945 0.3048)
			(stroke
				(width 0.1)
				(type default)
			)
			(layer "F.Fab")
		)
		(fp_line
			(start -0.67945 0.3048)
			(end -0.67945 -0.305054)
			(stroke
				(width 0.1)
				(type default)
			)
			(layer "F.Fab")
		)
		(pad "1" smd rect
			(at -0.40005 0 270)
			(size 0.4572 0.508)
			(layers "F.Cu" "F.Mask" "F.Paste")
			(net "USB2_PCH_0_R_DP")
		)
		(pad "2" smd rect
			(at 0.40005 0 270)
			(size 0.4572 0.508)
			(layers "F.Cu" "F.Mask" "F.Paste")
			(net "USB2_0_DP")
		)
	)
	(footprint ""
		(layer "F.Cu")
		(at 81.424018 -15.177262 180)
		(property "Reference" "PD108"
			(at -4.814824 -0.9271 0)
			(unlocked yes)
			(layer "F.SilkS")
			(effects
				(font
					(size 0.7874 0.5842)
					(thickness 0.1524)
				)
				(justify left)
			)
		)
		(property "Value" ""
			(at 0 0 180)
			(layer "F.Fab")
			(effects
				(font
					(size 1.27 1.27)
				)
			)
		)
		(duplicate_pad_numbers_are_jumpers no)
		(fp_line
			(start 4.107942 1.459992)
			(end -3.400044 1.459992)
			(stroke
				(width 0.1524)
				(type default)
			)
			(layer "F.SilkS")
		)
		(fp_line
			(start 4.107942 -1.459992)
			(end 4.107942 1.459992)
			(stroke
				(width 0.1524)
				(type default)
			)
			(layer "F.SilkS")
		)
		(fp_line
			(start -3.400044 1.459992)
			(end -3.400044 -1.459992)
			(stroke
				(width 0.1524)
				(type default)
			)
			(layer "F.SilkS")
		)
		(fp_line
			(start -3.400044 -1.459992)
			(end 4.107942 -1.459992)
			(stroke
				(width 0.1524)
				(type default)
			)
			(layer "F.SilkS")
		)
		(fp_rect
			(start 4.107942 -1.459992)
			(end 3.308096 1.459992)
			(stroke
				(width 0)
				(type default)
			)
			(fill yes)
			(layer "F.SilkS")
		)
		(fp_line
			(start 2.29997 1.459992)
			(end -2.29997 1.459992)
			(stroke
				(width 0.1)
				(type default)
			)
			(layer "F.Fab")
		)
		(fp_line
			(start 2.29997 -1.459992)
			(end 2.29997 1.459992)
			(stroke
				(width 0.1)
				(type default)
			)
			(layer "F.Fab")
		)
		(fp_line
			(start -2.29997 1.459992)
			(end -2.29997 -1.459992)
			(stroke
				(width 0.1)
				(type default)
			)
			(layer "F.Fab")
		)
		(fp_line
			(start -2.29997 -1.459992)
			(end 2.29997 -1.459992)
			(stroke
				(width 0.1)
				(type default)
			)
			(layer "F.Fab")
		)
		(fp_text user "-"
			(at 5.4102 0.29845 0)
			(unlocked yes)
			(layer "F.SilkS")
			(effects
				(font
					(size 1.905 1.4224)
					(thickness 0.1524)
				)
				(justify left)
			)
		)
		(fp_text user "+"
			(at -4.7752 -0.12065 180)
			(unlocked yes)
			(layer "F.SilkS")
			(effects
				(font
					(size 1.905 1.4224)
					(thickness 0.1524)
				)
				(justify left)
			)
		)
		(fp_text user "-"
			(at 5.4102 0.29845 0)
			(unlocked yes)
			(layer "F.Fab")
			(effects
				(font
					(size 1.905 1.4224)
					(thickness 0.1524)
				)
				(justify left)
			)
		)
		(fp_text user "+"
			(at -4.7752 -0.12065 180)
			(unlocked yes)
			(layer "F.Fab")
			(effects
				(font
					(size 1.905 1.4224)
					(thickness 0.1524)
				)
				(justify left)
			)
		)
		(pad "A" smd rect
			(at -1.999996 0 270)
			(size 1.7018 2.5146)
			(layers "F.Cu" "F.Mask" "F.Paste")
			(net "GND")
		)
		(pad "C" smd rect
			(at 1.999996 0 270)
			(size 1.7018 2.5146)
			(layers "F.Cu" "F.Mask" "F.Paste")
			(net "P12V_OCP_V3_2")
		)
	)
	(footprint ""
		(layer "F.Cu")
		(at 153.21788 -114.137948 180)
		(property "Reference" "R3236"
			(at 0 0 180)
			(layer "F.SilkS")
			(hide yes)
			(effects
				(font
					(size 1.27 1.27)
				)
			)
		)
		(property "Value" ""
			(at 0 0 180)
			(layer "F.Fab")
			(effects
				(font
					(size 1.27 1.27)
				)
			)
		)
		(duplicate_pad_numbers_are_jumpers no)
		(fp_line
			(start 0.7874 0.4064)
			(end -0.7874 0.4064)
			(stroke
				(width 0.1524)
				(type default)
			)
			(layer "F.SilkS")
		)
		(fp_line
			(start 0.7874 -0.4064)
			(end 0.7874 0.4064)
			(stroke
				(width 0.1524)
				(type default)
			)
			(layer "F.SilkS")
		)
		(fp_line
			(start -0.7874 0.4064)
			(end -0.7874 -0.4064)
			(stroke
				(width 0.1524)
				(type default)
			)
			(layer "F.SilkS")
		)
		(fp_line
			(start -0.7874 -0.4064)
			(end 0.7874 -0.4064)
			(stroke
				(width 0.1524)
				(type default)
			)
			(layer "F.SilkS")
		)
		(fp_line
			(start 0.67945 0.3048)
			(end 0.120396 0.3048)
			(stroke
				(width 0.1)
				(type default)
			)
			(layer "F.Fab")
		)
		(fp_line
			(start 0.67945 -0.3048)
			(end 0.67945 0.3048)
			(stroke
				(width 0.1)
				(type default)
			)
			(layer "F.Fab")
		)
		(fp_line
			(start 0.12065 -0.2794)
			(end 0.12065 -0.3048)
			(stroke
				(width 0.1)
				(type default)
			)
			(layer "F.Fab")
		)
		(fp_line
			(start 0.12065 -0.3048)
			(end 0.67945 -0.3048)
			(stroke
				(width 0.1)
				(type default)
			)
			(layer "F.Fab")
		)
		(fp_line
			(start 0.120396 0.3048)
			(end 0.120396 0.2794)
			(stroke
				(width 0.1)
				(type default)
			)
			(layer "F.Fab")
		)
		(fp_line
			(start 0.120396 0.2794)
			(end -0.12065 0.2794)
			(stroke
				(width 0.1)
				(type default)
			)
			(layer "F.Fab")
		)
		(fp_line
			(start -0.12065 0.3048)
			(end -0.67945 0.3048)
			(stroke
				(width 0.1)
				(type default)
			)
			(layer "F.Fab")
		)
		(fp_line
			(start -0.12065 0.2794)
			(end -0.12065 0.3048)
			(stroke
				(width 0.1)
				(type default)
			)
			(layer "F.Fab")
		)
		(fp_line
			(start -0.12065 -0.2794)
			(end 0.12065 -0.2794)
			(stroke
				(width 0.1)
				(type default)
			)
			(layer "F.Fab")
		)
		(fp_line
			(start -0.12065 -0.305054)
			(end -0.12065 -0.2794)
			(stroke
				(width 0.1)
				(type default)
			)
			(layer "F.Fab")
		)
		(fp_line
			(start -0.67945 0.3048)
			(end -0.67945 -0.305054)
			(stroke
				(width 0.1)
				(type default)
			)
			(layer "F.Fab")
		)
		(fp_line
			(start -0.67945 -0.305054)
			(end -0.12065 -0.305054)
			(stroke
				(width 0.1)
				(type default)
			)
			(layer "F.Fab")
		)
		(pad "1" smd circle
			(at -0.40005 0 180)
			(size 0 0)
			(layers "F.Cu" "F.Mask" "F.Paste")
			(net "RST_HP_OCP_V3_2_R_N")
		)
		(pad "2" smd circle
			(at 0.40005 0 180)
			(size 0 0)
			(layers "F.Cu" "F.Mask" "F.Paste")
			(net "RST_SMB_OCP_V3_2_N")
		)
	)
	(footprint ""
		(layer "F.Cu")
		(at 334.385412 -21.60778 -90)
		(property "Reference" "U61"
			(at -1.967738 -5.486908 0)
			(unlocked yes)
			(layer "F.SilkS")
			(effects
				(font
					(size 0.7874 0.5842)
					(thickness 0.1524)
				)
			)
		)
		(property "Value" ""
			(at 0 0 270)
			(layer "F.Fab")
			(effects
				(font
					(size 1.27 1.27)
				)
			)
		)
		(duplicate_pad_numbers_are_jumpers no)
		(fp_line
			(start -1.7272 1.1176)
			(end -1.7272 -1.1176)
			(stroke
				(width 0.1524)
				(type default)
			)
			(layer "F.SilkS")
		)
		(fp_line
			(start 1.7272 1.1176)
			(end -1.7272 1.1176)
			(stroke
				(width 0.1524)
				(type default)
			)
			(layer "F.SilkS")
		)
		(fp_line
			(start 0 -0.7366)
			(end -0.254 -1.1176)
			(stroke
				(width 0.1524)
				(type default)
			)
			(layer "F.SilkS")
		)
		(fp_line
			(start -0.254 -1.1176)
			(end -1.7272 -1.1176)
			(stroke
				(width 0.1524)
				(type default)
			)
			(layer "F.SilkS")
		)
		(fp_line
			(start 0.254 -1.1176)
			(end 0 -0.7366)
			(stroke
				(width 0.1524)
				(type default)
			)
			(layer "F.SilkS")
		)
		(fp_line
			(start 1.7272 -1.1176)
			(end 1.7272 1.1176)
			(stroke
				(width 0.1524)
				(type default)
			)
			(layer "F.SilkS")
		)
		(fp_line
			(start 1.7272 -1.1176)
			(end 0.254 -1.1176)
			(stroke
				(width 0.1524)
				(type default)
			)
			(layer "F.SilkS")
		)
		(fp_poly
			(pts
				(xy -2.699766 -0.808736) (xy -2.440686 -1.525524) (xy -1.853692 -0.90805)
			)
			(stroke
				(width 0)
				(type default)
			)
			(fill yes)
			(layer "F.SilkS")
		)
		(fp_line
			(start -1.5748 1.1176)
			(end 1.5748 1.1176)
			(stroke
				(width 0.1)
				(type default)
			)
			(layer "F.Fab")
		)
		(fp_line
			(start 1.5748 1.1176)
			(end 1.5748 -1.1176)
			(stroke
				(width 0.1)
				(type default)
			)
			(layer "F.Fab")
		)
		(fp_line
			(start -1.5748 -1.1176)
			(end -1.5748 1.1176)
			(stroke
				(width 0.1)
				(type default)
			)
			(layer "F.Fab")
		)
		(fp_line
			(start 1.5748 -1.1176)
			(end -1.5748 -1.1176)
			(stroke
				(width 0.1)
				(type default)
			)
			(layer "F.Fab")
		)
		(fp_poly
			(pts
				(xy -1.9558 -0.649986) (xy -2.7178 -0.268986) (xy -2.7178 -1.030986)
			)
			(stroke
				(width 0)
				(type default)
			)
			(fill yes)
			(layer "F.Fab")
		)
		(pad "1" smd rect
			(at -0.999998 -0.649986 180)
			(size 0.3556 1.1176)
			(layers "F.Cu" "F.Mask" "F.Paste")
			(net "RST_ESPI_RESET_N_R")
		)
		(pad "2" smd rect
			(at -0.999998 0 180)
			(size 0.3556 1.1176)
			(layers "F.Cu" "F.Mask" "F.Paste")
			(net "GND")
		)
		(pad "3" smd rect
			(at -0.999998 0.649986 180)
			(size 0.3556 1.1176)
			(layers "F.Cu" "F.Mask" "F.Paste")
			(net "RST_PLTRST_B_MUX_N")
		)
		(pad "4" smd rect
			(at 0.999998 0.649986 180)
			(size 0.3556 1.1176)
			(layers "F.Cu" "F.Mask" "F.Paste")
			(net "ESPI_BMC_LPC_RST_N")
		)
		(pad "5" smd rect
			(at 0.999998 0 180)
			(size 0.3556 1.1176)
			(layers "F.Cu" "F.Mask" "F.Paste")
			(net "PGPPA_AUX")
		)
		(pad "6" smd rect
			(at 0.999998 -0.649986 180)
			(size 0.3556 1.1176)
			(layers "F.Cu" "F.Mask" "F.Paste")
			(net "FM_ESPI_PLD_EN")
		)
	)
)
